(kicad_pcb
	(version 20260206)
	(generator "pcbnew")
	(generator_version "10.0")
	(general
		(thickness 1.6)
		(legacy_teardrops no)
	)
	(paper "A4")
	(title_block
		(title "04192023_DAF0TMB3IC0_F0TG_MB_C_brd_V02_OCP.brd")
		(comment 1 "Grand Teton / footprints 5772-5778 of 8354")
	)
	(layers
		(0 "F.Cu" signal "TOP")
		(4 "In1.Cu" signal "GND")
		(6 "In2.Cu" signal "IN1")
		(8 "In3.Cu" signal "GND1")
		(10 "In4.Cu" signal "IN2")
		(12 "In5.Cu" signal "GND2")
		(14 "In6.Cu" signal "IN3")
		(16 "In7.Cu" signal "GND3")
		(18 "In8.Cu" signal "VCC")
		(20 "In9.Cu" signal "VCC1")
		(22 "In10.Cu" signal "GND4")
		(24 "In11.Cu" signal "IN4")
		(26 "In12.Cu" signal "GND5")
		(28 "In13.Cu" signal "IN5")
		(30 "In14.Cu" signal "GND6")
		(32 "In15.Cu" signal "IN6")
		(34 "In16.Cu" signal "GND7")
		(2 "B.Cu" signal "BOTTOM")
		(9 "F.Adhes" user "F.Adhesive")
		(11 "B.Adhes" user "B.Adhesive")
		(13 "F.Paste" user "Package Geometry/Pastemask Top")
		(15 "B.Paste" user "Package Geometry/Pastemask Bottom")
		(5 "F.SilkS" user "Ref Des/Silkscreen Top")
		(7 "B.SilkS" user "Ref Des/Silkscreen Bottom")
		(1 "F.Mask" user "Board Geometry/Soldermask Top")
		(3 "B.Mask" user "Board Geometry/Soldermask Bottom")
		(17 "Dwgs.User" user "User.Drawings")
		(19 "Cmts.User" user "User.Comments")
		(21 "Eco1.User" user "User.Eco1")
		(23 "Eco2.User" user "User.Eco2")
		(25 "Edge.Cuts" user "Board Geometry/Outline")
		(27 "Margin" user)
		(31 "F.CrtYd" user "Package Geometry/Place Bound Top")
		(29 "B.CrtYd" user "Package Geometry/Place Bound Bottom")
		(35 "F.Fab" user "Ref Des/Assembly Top")
		(33 "B.Fab" user "Ref Des/Assembly Bottom")
	)
	(footprint ""
		(layer "B.Cu")
		(at 117.094 -417.957 -90)
		(property "Reference" "R3502"
			(at 0 0 90)
			(layer "B.SilkS")
			(hide yes)
			(effects
				(font
					(size 1.27 1.27)
				)
				(justify mirror)
			)
		)
		(property "Value" ""
			(at 0 0 90)
			(layer "B.Fab")
			(effects
				(font
					(size 1.27 1.27)
				)
				(justify mirror)
			)
		)
		(duplicate_pad_numbers_are_jumpers no)
		(fp_line
			(start -0.7874 0.4064)
			(end 0.7874 0.4064)
			(stroke
				(width 0.1524)
				(type default)
			)
			(layer "B.SilkS")
		)
		(fp_line
			(start 0.7874 0.4064)
			(end 0.7874 -0.4064)
			(stroke
				(width 0.1524)
				(type default)
			)
			(layer "B.SilkS")
		)
		(fp_line
			(start -0.7874 -0.4064)
			(end -0.7874 0.4064)
			(stroke
				(width 0.1524)
				(type default)
			)
			(layer "B.SilkS")
		)
		(fp_line
			(start 0.7874 -0.4064)
			(end -0.7874 -0.4064)
			(stroke
				(width 0.1524)
				(type default)
			)
			(layer "B.SilkS")
		)
		(fp_line
			(start -0.67945 0.3048)
			(end -0.120396 0.3048)
			(stroke
				(width 0.1)
				(type default)
			)
			(layer "B.Fab")
		)
		(fp_line
			(start -0.120396 0.3048)
			(end -0.120396 0.2794)
			(stroke
				(width 0.1)
				(type default)
			)
			(layer "B.Fab")
		)
		(fp_line
			(start 0.12065 0.3048)
			(end 0.67945 0.3048)
			(stroke
				(width 0.1)
				(type default)
			)
			(layer "B.Fab")
		)
		(fp_line
			(start 0.67945 0.3048)
			(end 0.67945 -0.305054)
			(stroke
				(width 0.1)
				(type default)
			)
			(layer "B.Fab")
		)
		(fp_line
			(start -0.120396 0.2794)
			(end 0.12065 0.2794)
			(stroke
				(width 0.1)
				(type default)
			)
			(layer "B.Fab")
		)
		(fp_line
			(start 0.12065 0.2794)
			(end 0.12065 0.3048)
			(stroke
				(width 0.1)
				(type default)
			)
			(layer "B.Fab")
		)
		(fp_line
			(start -0.12065 -0.2794)
			(end -0.12065 -0.3048)
			(stroke
				(width 0.1)
				(type default)
			)
			(layer "B.Fab")
		)
		(fp_line
			(start 0.12065 -0.2794)
			(end -0.12065 -0.2794)
			(stroke
				(width 0.1)
				(type default)
			)
			(layer "B.Fab")
		)
		(fp_line
			(start -0.67945 -0.3048)
			(end -0.67945 0.3048)
			(stroke
				(width 0.1)
				(type default)
			)
			(layer "B.Fab")
		)
		(fp_line
			(start -0.12065 -0.3048)
			(end -0.67945 -0.3048)
			(stroke
				(width 0.1)
				(type default)
			)
			(layer "B.Fab")
		)
		(fp_line
			(start 0.12065 -0.305054)
			(end 0.12065 -0.2794)
			(stroke
				(width 0.1)
				(type default)
			)
			(layer "B.Fab")
		)
		(fp_line
			(start 0.67945 -0.305054)
			(end 0.12065 -0.305054)
			(stroke
				(width 0.1)
				(type default)
			)
			(layer "B.Fab")
		)
		(pad "1" smd circle
			(at 0.40005 0 90)
			(size 0 0)
			(layers "B.Cu" "B.Mask" "B.Paste")
			(net "GPU_FPGA_EROT_FATALERR_N")
		)
		(pad "2" smd circle
			(at -0.40005 0 90)
			(size 0 0)
			(layers "B.Cu" "B.Mask" "B.Paste")
			(net "GND")
		)
	)
	(footprint ""
		(layer "B.Cu")
		(at 249.428 -246.634)
		(property "Reference" "ME14"
			(at 0 0 0)
			(layer "B.SilkS")
			(hide yes)
			(effects
				(font
					(size 1.27 1.27)
				)
				(justify mirror)
			)
		)
		(property "Value" ""
			(at 0 0 0)
			(layer "B.Fab")
			(effects
				(font
					(size 1.27 1.27)
				)
				(justify mirror)
			)
		)
		(duplicate_pad_numbers_are_jumpers no)
		(zone
			(layer "B.Cu")
			(hatch none 0.5)
			(connect_pads
				(clearance 0)
			)
			(min_thickness 0.25)
			(keepout
				(tracks allowed)
				(vias allowed)
				(pads allowed)
				(copperpour allowed)
				(footprints not_allowed)
			)
			(placement
				(enabled no)
				(sheetname "")
			)
			(fill
				(thermal_gap 0.5)
				(thermal_bridge_width 0.5)
				(island_removal_mode 0)
			)
			(polygon
				(pts
					(arc
						(start 259.42798 -246.634)
						(mid 239.42802 -246.634)
						(end 259.42798 -246.634)
					)
				)
			)
		)
	)
	(footprint ""
		(layer "B.Cu")
		(at 126.375668 -37.47643)
		(property "Reference" "C6074"
			(at 0 0 0)
			(layer "B.SilkS")
			(hide yes)
			(effects
				(font
					(size 1.27 1.27)
				)
				(justify mirror)
			)
		)
		(property "Value" ""
			(at 0 0 0)
			(layer "B.Fab")
			(effects
				(font
					(size 1.27 1.27)
				)
				(justify mirror)
			)
		)
		(duplicate_pad_numbers_are_jumpers no)
		(fp_line
			(start -0.7874 -0.4064)
			(end -0.7874 0.4064)
			(stroke
				(width 0.1524)
				(type default)
			)
			(layer "B.SilkS")
		)
		(fp_line
			(start -0.7874 0.4064)
			(end 0.7874 0.4064)
			(stroke
				(width 0.1524)
				(type default)
			)
			(layer "B.SilkS")
		)
		(fp_line
			(start 0.7874 -0.4064)
			(end -0.7874 -0.4064)
			(stroke
				(width 0.1524)
				(type default)
			)
			(layer "B.SilkS")
		)
		(fp_line
			(start 0.7874 0.4064)
			(end 0.7874 -0.4064)
			(stroke
				(width 0.1524)
				(type default)
			)
			(layer "B.SilkS")
		)
		(fp_line
			(start -0.67945 -0.3048)
			(end -0.67945 0.3048)
			(stroke
				(width 0.1)
				(type default)
			)
			(layer "B.Fab")
		)
		(fp_line
			(start -0.67945 0.3048)
			(end -0.120396 0.3048)
			(stroke
				(width 0.1)
				(type default)
			)
			(layer "B.Fab")
		)
		(fp_line
			(start -0.12065 -0.3048)
			(end -0.67945 -0.3048)
			(stroke
				(width 0.1)
				(type default)
			)
			(layer "B.Fab")
		)
		(fp_line
			(start -0.12065 -0.2794)
			(end -0.12065 -0.3048)
			(stroke
				(width 0.1)
				(type default)
			)
			(layer "B.Fab")
		)
		(fp_line
			(start -0.120396 0.2794)
			(end 0.12065 0.2794)
			(stroke
				(width 0.1)
				(type default)
			)
			(layer "B.Fab")
		)
		(fp_line
			(start -0.120396 0.3048)
			(end -0.120396 0.2794)
			(stroke
				(width 0.1)
				(type default)
			)
			(layer "B.Fab")
		)
		(fp_line
			(start 0.12065 -0.305054)
			(end 0.12065 -0.2794)
			(stroke
				(width 0.1)
				(type default)
			)
			(layer "B.Fab")
		)
		(fp_line
			(start 0.12065 -0.2794)
			(end -0.12065 -0.2794)
			(stroke
				(width 0.1)
				(type default)
			)
			(layer "B.Fab")
		)
		(fp_line
			(start 0.12065 0.2794)
			(end 0.12065 0.3048)
			(stroke
				(width 0.1)
				(type default)
			)
			(layer "B.Fab")
		)
		(fp_line
			(start 0.12065 0.3048)
			(end 0.67945 0.3048)
			(stroke
				(width 0.1)
				(type default)
			)
			(layer "B.Fab")
		)
		(fp_line
			(start 0.67945 -0.305054)
			(end 0.12065 -0.305054)
			(stroke
				(width 0.1)
				(type default)
			)
			(layer "B.Fab")
		)
		(fp_line
			(start 0.67945 0.3048)
			(end 0.67945 -0.305054)
			(stroke
				(width 0.1)
				(type default)
			)
			(layer "B.Fab")
		)
		(pad "1" smd circle
			(at 0.40005 0 180)
			(size 0 0)
			(layers "B.Cu" "B.Mask" "B.Paste")
			(net "P1V2_AUX")
		)
		(pad "2" smd circle
			(at -0.40005 0 180)
			(size 0 0)
			(layers "B.Cu" "B.Mask" "B.Paste")
			(net "GND")
		)
	)
	(footprint ""
		(layer "B.Cu")
		(at 183.932322 -115.022376)
		(property "Reference" "C1176"
			(at 0 0 0)
			(layer "B.SilkS")
			(hide yes)
			(effects
				(font
					(size 1.27 1.27)
				)
				(justify mirror)
			)
		)
		(property "Value" ""
			(at 0 0 0)
			(layer "B.Fab")
			(effects
				(font
					(size 1.27 1.27)
				)
				(justify mirror)
			)
		)
		(duplicate_pad_numbers_are_jumpers no)
		(fp_line
			(start -0.69215 -0.2921)
			(end -0.69215 0.2921)
			(stroke
				(width 0.1524)
				(type default)
			)
			(layer "B.SilkS")
		)
		(fp_line
			(start -0.69215 0.2921)
			(end 0.69215 0.2921)
			(stroke
				(width 0.1524)
				(type default)
			)
			(layer "B.SilkS")
		)
		(fp_line
			(start 0.69215 -0.2921)
			(end -0.69215 -0.2921)
			(stroke
				(width 0.1524)
				(type default)
			)
			(layer "B.SilkS")
		)
		(fp_line
			(start 0.69215 0.2921)
			(end 0.69215 -0.2921)
			(stroke
				(width 0.1524)
				(type default)
			)
			(layer "B.SilkS")
		)
		(fp_line
			(start -0.51435 -0.2794)
			(end -0.51435 0.2794)
			(stroke
				(width 0.1)
				(type default)
			)
			(layer "B.Fab")
		)
		(fp_line
			(start -0.51435 0.2794)
			(end 0.51435 0.2794)
			(stroke
				(width 0.1)
				(type default)
			)
			(layer "B.Fab")
		)
		(fp_line
			(start 0.51435 -0.2794)
			(end -0.51435 -0.2794)
			(stroke
				(width 0.1)
				(type default)
			)
			(layer "B.Fab")
		)
		(fp_line
			(start 0.51435 0.2794)
			(end 0.51435 -0.2794)
			(stroke
				(width 0.1)
				(type default)
			)
			(layer "B.Fab")
		)
		(pad "1" smd circle
			(at 0.40005 0 180)
			(size 0 0)
			(layers "B.Cu" "B.Mask" "B.Paste")
			(net "P3V3_AUX")
		)
		(pad "2" smd circle
			(at -0.40005 0 180)
			(size 0 0)
			(layers "B.Cu" "B.Mask" "B.Paste")
			(net "GND")
		)
		(zone
			(layer "B.Cu")
			(hatch none 0.5)
			(connect_pads
				(clearance 0)
			)
			(min_thickness 0.25)
			(keepout
				(tracks not_allowed)
				(vias allowed)
				(pads allowed)
				(copperpour not_allowed)
				(footprints allowed)
			)
			(placement
				(enabled no)
				(sheetname "")
			)
			(fill
				(thermal_gap 0.5)
				(thermal_bridge_width 0.5)
				(island_removal_mode 0)
			)
			(polygon
				(pts
					(xy 183.741822 -114.934746) (xy 183.741822 -115.110006) (xy 183.831992 -115.168426) (xy 184.031382 -115.168426)
					(xy 184.122822 -115.11026) (xy 184.122822 -114.934746) (xy 184.031382 -114.87658) (xy 183.831992 -114.87658)
				)
			)
		)
	)
	(footprint ""
		(layer "B.Cu")
		(at 145.124678 -318.208152 180)
		(property "Reference" "R1501"
			(at 0 0 0)
			(layer "B.SilkS")
			(hide yes)
			(effects
				(font
					(size 1.27 1.27)
				)
				(justify mirror)
			)
		)
		(property "Value" ""
			(at 0 0 0)
			(layer "B.Fab")
			(effects
				(font
					(size 1.27 1.27)
				)
				(justify mirror)
			)
		)
		(duplicate_pad_numbers_are_jumpers no)
		(fp_line
			(start 0.7874 0.4064)
			(end 0.7874 -0.4064)
			(stroke
				(width 0.1524)
				(type default)
			)
			(layer "B.SilkS")
		)
		(fp_line
			(start 0.7874 -0.4064)
			(end -0.7874 -0.4064)
			(stroke
				(width 0.1524)
				(type default)
			)
			(layer "B.SilkS")
		)
		(fp_line
			(start -0.7874 0.4064)
			(end 0.7874 0.4064)
			(stroke
				(width 0.1524)
				(type default)
			)
			(layer "B.SilkS")
		)
		(fp_line
			(start -0.7874 -0.4064)
			(end -0.7874 0.4064)
			(stroke
				(width 0.1524)
				(type default)
			)
			(layer "B.SilkS")
		)
		(fp_line
			(start 0.67945 0.3048)
			(end 0.67945 -0.305054)
			(stroke
				(width 0.1)
				(type default)
			)
			(layer "B.Fab")
		)
		(fp_line
			(start 0.67945 -0.305054)
			(end 0.12065 -0.305054)
			(stroke
				(width 0.1)
				(type default)
			)
			(layer "B.Fab")
		)
		(fp_line
			(start 0.12065 0.3048)
			(end 0.67945 0.3048)
			(stroke
				(width 0.1)
				(type default)
			)
			(layer "B.Fab")
		)
		(fp_line
			(start 0.12065 0.2794)
			(end 0.12065 0.3048)
			(stroke
				(width 0.1)
				(type default)
			)
			(layer "B.Fab")
		)
		(fp_line
			(start 0.12065 -0.2794)
			(end -0.12065 -0.2794)
			(stroke
				(width 0.1)
				(type default)
			)
			(layer "B.Fab")
		)
		(fp_line
			(start 0.12065 -0.305054)
			(end 0.12065 -0.2794)
			(stroke
				(width 0.1)
				(type default)
			)
			(layer "B.Fab")
		)
		(fp_line
			(start -0.120396 0.3048)
			(end -0.120396 0.2794)
			(stroke
				(width 0.1)
				(type default)
			)
			(layer "B.Fab")
		)
		(fp_line
			(start -0.120396 0.2794)
			(end 0.12065 0.2794)
			(stroke
				(width 0.1)
				(type default)
			)
			(layer "B.Fab")
		)
		(fp_line
			(start -0.12065 -0.2794)
			(end -0.12065 -0.3048)
			(stroke
				(width 0.1)
				(type default)
			)
			(layer "B.Fab")
		)
		(fp_line
			(start -0.12065 -0.3048)
			(end -0.67945 -0.3048)
			(stroke
				(width 0.1)
				(type default)
			)
			(layer "B.Fab")
		)
		(fp_line
			(start -0.67945 0.3048)
			(end -0.120396 0.3048)
			(stroke
				(width 0.1)
				(type default)
			)
			(layer "B.Fab")
		)
		(fp_line
			(start -0.67945 -0.3048)
			(end -0.67945 0.3048)
			(stroke
				(width 0.1)
				(type default)
			)
			(layer "B.Fab")
		)
		(pad "1" smd circle
			(at 0.40005 0)
			(size 0 0)
			(layers "B.Cu" "B.Mask" "B.Paste")
			(net "PVDD18_S5_P1")
		)
		(pad "2" smd circle
			(at -0.40005 0)
			(size 0 0)
			(layers "B.Cu" "B.Mask" "B.Paste")
			(net "CLK_CPU1_RTCCLK")
		)
	)
	(footprint ""
		(layer "B.Cu")
		(at 229.997 -240.03)
		(property "Reference" "R143"
			(at 0 0 0)
			(layer "B.SilkS")
			(hide yes)
			(effects
				(font
					(size 1.27 1.27)
				)
				(justify mirror)
			)
		)
		(property "Value" ""
			(at 0 0 0)
			(layer "B.Fab")
			(effects
				(font
					(size 1.27 1.27)
				)
				(justify mirror)
			)
		)
		(duplicate_pad_numbers_are_jumpers no)
		(fp_line
			(start -0.7874 -0.4064)
			(end -0.7874 0.4064)
			(stroke
				(width 0.1524)
				(type default)
			)
			(layer "B.SilkS")
		)
		(fp_line
			(start -0.7874 0.4064)
			(end 0.7874 0.4064)
			(stroke
				(width 0.1524)
				(type default)
			)
			(layer "B.SilkS")
		)
		(fp_line
			(start 0.7874 -0.4064)
			(end -0.7874 -0.4064)
			(stroke
				(width 0.1524)
				(type default)
			)
			(layer "B.SilkS")
		)
		(fp_line
			(start 0.7874 0.4064)
			(end 0.7874 -0.4064)
			(stroke
				(width 0.1524)
				(type default)
			)
			(layer "B.SilkS")
		)
		(fp_line
			(start -0.67945 -0.3048)
			(end -0.67945 0.3048)
			(stroke
				(width 0.1)
				(type default)
			)
			(layer "B.Fab")
		)
		(fp_line
			(start -0.67945 0.3048)
			(end -0.120396 0.3048)
			(stroke
				(width 0.1)
				(type default)
			)
			(layer "B.Fab")
		)
		(fp_line
			(start -0.12065 -0.3048)
			(end -0.67945 -0.3048)
			(stroke
				(width 0.1)
				(type default)
			)
			(layer "B.Fab")
		)
		(fp_line
			(start -0.12065 -0.2794)
			(end -0.12065 -0.3048)
			(stroke
				(width 0.1)
				(type default)
			)
			(layer "B.Fab")
		)
		(fp_line
			(start -0.120396 0.2794)
			(end 0.12065 0.2794)
			(stroke
				(width 0.1)
				(type default)
			)
			(layer "B.Fab")
		)
		(fp_line
			(start -0.120396 0.3048)
			(end -0.120396 0.2794)
			(stroke
				(width 0.1)
				(type default)
			)
			(layer "B.Fab")
		)
		(fp_line
			(start 0.12065 -0.305054)
			(end 0.12065 -0.2794)
			(stroke
				(width 0.1)
				(type default)
			)
			(layer "B.Fab")
		)
		(fp_line
			(start 0.12065 -0.2794)
			(end -0.12065 -0.2794)
			(stroke
				(width 0.1)
				(type default)
			)
			(layer "B.Fab")
		)
		(fp_line
			(start 0.12065 0.2794)
			(end 0.12065 0.3048)
			(stroke
				(width 0.1)
				(type default)
			)
			(layer "B.Fab")
		)
		(fp_line
			(start 0.12065 0.3048)
			(end 0.67945 0.3048)
			(stroke
				(width 0.1)
				(type default)
			)
			(layer "B.Fab")
		)
		(fp_line
			(start 0.67945 -0.305054)
			(end 0.12065 -0.305054)
			(stroke
				(width 0.1)
				(type default)
			)
			(layer "B.Fab")
		)
		(fp_line
			(start 0.67945 0.3048)
			(end 0.67945 -0.305054)
			(stroke
				(width 0.1)
				(type default)
			)
			(layer "B.Fab")
		)
		(pad "1" smd circle
			(at 0.40005 0 180)
			(size 0 0)
			(layers "B.Cu" "B.Mask" "B.Paste")
			(net "SMB_CPU0_CPU1_APML_MUX1_SDA")
		)
		(pad "2" smd circle
			(at -0.40005 0 180)
			(size 0 0)
			(layers "B.Cu" "B.Mask" "B.Paste")
			(net "SMB_APML_CPU0_R_SDA")
		)
	)
	(footprint ""
		(layer "B.Cu")
		(at 358.467152 -261.747762 90)
		(property "Reference" "C2617"
			(at 0 0 90)
			(layer "B.SilkS")
			(hide yes)
			(effects
				(font
					(size 1.27 1.27)
				)
				(justify mirror)
			)
		)
		(property "Value" ""
			(at 0 0 90)
			(layer "B.Fab")
			(effects
				(font
					(size 1.27 1.27)
				)
				(justify mirror)
			)
		)
		(duplicate_pad_numbers_are_jumpers no)
		(fp_line
			(start 0.7874 -0.4064)
			(end -0.7874 -0.4064)
			(stroke
				(width 0.1524)
				(type default)
			)
			(layer "B.SilkS")
		)
		(fp_line
			(start -0.7874 -0.4064)
			(end -0.7874 0.4064)
			(stroke
				(width 0.1524)
				(type default)
			)
			(layer "B.SilkS")
		)
		(fp_line
			(start 0.7874 0.4064)
			(end 0.7874 -0.4064)
			(stroke
				(width 0.1524)
				(type default)
			)
			(layer "B.SilkS")
		)
		(fp_line
			(start -0.7874 0.4064)
			(end 0.7874 0.4064)
			(stroke
				(width 0.1524)
				(type default)
			)
			(layer "B.SilkS")
		)
		(fp_line
			(start 0.67945 -0.305054)
			(end 0.12065 -0.305054)
			(stroke
				(width 0.1)
				(type default)
			)
			(layer "B.Fab")
		)
		(fp_line
			(start 0.12065 -0.305054)
			(end 0.12065 -0.2794)
			(stroke
				(width 0.1)
				(type default)
			)
			(layer "B.Fab")
		)
		(fp_line
			(start -0.12065 -0.3048)
			(end -0.67945 -0.3048)
			(stroke
				(width 0.1)
				(type default)
			)
			(layer "B.Fab")
		)
		(fp_line
			(start -0.67945 -0.3048)
			(end -0.67945 0.3048)
			(stroke
				(width 0.1)
				(type default)
			)
			(layer "B.Fab")
		)
		(fp_line
			(start 0.12065 -0.2794)
			(end -0.12065 -0.2794)
			(stroke
				(width 0.1)
				(type default)
			)
			(layer "B.Fab")
		)
		(fp_line
			(start -0.12065 -0.2794)
			(end -0.12065 -0.3048)
			(stroke
				(width 0.1)
				(type default)
			)
			(layer "B.Fab")
		)
		(fp_line
			(start 0.12065 0.2794)
			(end 0.12065 0.3048)
			(stroke
				(width 0.1)
				(type default)
			)
			(layer "B.Fab")
		)
		(fp_line
			(start -0.120396 0.2794)
			(end 0.12065 0.2794)
			(stroke
				(width 0.1)
				(type default)
			)
			(layer "B.Fab")
		)
		(fp_line
			(start 0.67945 0.3048)
			(end 0.67945 -0.305054)
			(stroke
				(width 0.1)
				(type default)
			)
			(layer "B.Fab")
		)
		(fp_line
			(start 0.12065 0.3048)
			(end 0.67945 0.3048)
			(stroke
				(width 0.1)
				(type default)
			)
			(layer "B.Fab")
		)
		(fp_line
			(start -0.120396 0.3048)
			(end -0.120396 0.2794)
			(stroke
				(width 0.1)
				(type default)
			)
			(layer "B.Fab")
		)
		(fp_line
			(start -0.67945 0.3048)
			(end -0.120396 0.3048)
			(stroke
				(width 0.1)
				(type default)
			)
			(layer "B.Fab")
		)
		(pad "1" smd circle
			(at 0.40005 0 270)
			(size 0 0)
			(layers "B.Cu" "B.Mask" "B.Paste")
			(net "PVDD11_S3_P0")
		)
		(pad "2" smd circle
			(at -0.40005 0 270)
			(size 0 0)
			(layers "B.Cu" "B.Mask" "B.Paste")
			(net "GND")
		)
	)
)
